(kicad_pcb
	(version 20260206)
	(generator "pcbnew")
	(generator_version "10.0")
	(general
		(thickness 1.6)
		(legacy_teardrops no)
	)
	(paper "A4")
	(title_block
		(title "04192023_DAF0TMB3IC0_F0TG_MB_C_brd_V02_OCP.brd")
		(comment 1 "Grand Teton / footprints 3845-3845 of 8354")
	)
	(layers
		(0 "F.Cu" signal "TOP")
		(4 "In1.Cu" signal "GND")
		(6 "In2.Cu" signal "IN1")
		(8 "In3.Cu" signal "GND1")
		(10 "In4.Cu" signal "IN2")
		(12 "In5.Cu" signal "GND2")
		(14 "In6.Cu" signal "IN3")
		(16 "In7.Cu" signal "GND3")
		(18 "In8.Cu" signal "VCC")
		(20 "In9.Cu" signal "VCC1")
		(22 "In10.Cu" signal "GND4")
		(24 "In11.Cu" signal "IN4")
		(26 "In12.Cu" signal "GND5")
		(28 "In13.Cu" signal "IN5")
		(30 "In14.Cu" signal "GND6")
		(32 "In15.Cu" signal "IN6")
		(34 "In16.Cu" signal "GND7")
		(2 "B.Cu" signal "BOTTOM")
		(9 "F.Adhes" user "F.Adhesive")
		(11 "B.Adhes" user "B.Adhesive")
		(13 "F.Paste" user "Package Geometry/Pastemask Top")
		(15 "B.Paste" user "Package Geometry/Pastemask Bottom")
		(5 "F.SilkS" user "Ref Des/Silkscreen Top")
		(7 "B.SilkS" user "Ref Des/Silkscreen Bottom")
		(1 "F.Mask" user "Board Geometry/Soldermask Top")
		(3 "B.Mask" user "Board Geometry/Soldermask Bottom")
		(17 "Dwgs.User" user "User.Drawings")
		(19 "Cmts.User" user "User.Comments")
		(21 "Eco1.User" user "User.Eco1")
		(23 "Eco2.User" user "User.Eco2")
		(25 "Edge.Cuts" user "Board Geometry/Outline")
		(27 "Margin" user)
		(31 "F.CrtYd" user "Package Geometry/Place Bound Top")
		(29 "B.CrtYd" user "Package Geometry/Place Bound Bottom")
		(35 "F.Fab" user "Ref Des/Assembly Top")
		(33 "B.Fab" user "Ref Des/Assembly Bottom")
	)
	(footprint ""
		(layer "F.Cu")
		(at 22.742906 19.444716 -90)
		(property "Reference" "JP12_12"
			(at 0 0 270)
			(layer "F.SilkS")
			(hide yes)
			(effects
				(font
					(size 1.27 1.27)
				)
			)
		)
		(property "Value" ""
			(at 0 0 270)
			(layer "F.Fab")
			(effects
				(font
					(size 1.27 1.27)
				)
			)
		)
		(duplicate_pad_numbers_are_jumpers no)
		(pad "1" smd circle
			(at 0 0 270)
			(size 0.762 0.762)
			(layers "F.Cu" "F.Mask" "F.Paste")
			(net "Net_10794")
		)
	)
)
